# TIMECARD (Time Appliance Project (Time Card)) — schematic netlist excerpt (pin names and nets, part order shuffled) for the footprints in the layout excerpt that follows; sources: Cadence DE-HDL packaged netlist, KiCad conversion of R4006-B0001-02_R01.brd

R219  RESISTOR  10KOHM 1%  pkg SMC_0402R_H016  page 10 : \1\ = XP3R3V_FPGA ; \2\ = FPGA_BRD_REV0
R18  RESISTOR  4.7KOHM 1%  pkg SMC_0402R_H016  page 24 : \1\ = XP5R0V_FT4232 ; \2\ = FT_USB_DETECT

(kicad_pcb
	(version 20260206)
	(generator "pcbnew")
	(generator_version "10.0")
	(general
		(thickness 1.6)
		(legacy_teardrops no)
	)
	(paper "A4")
	(title_block
		(title "timecard-production-celestica-r4006 — R4006-B0001-02_R01.brd")
		(comment 1 "Time Appliance Project (Time Card) / footprints 821-822 of 1113")
	)
	(layers
		(0 "F.Cu" signal "TOP")
		(4 "In1.Cu" signal "L02_GND1")
		(6 "In2.Cu" signal "L03_SIG1")
		(8 "In3.Cu" signal "L04_GND2")
		(10 "In4.Cu" signal "L05_VCC1")
		(12 "In5.Cu" signal "L06_VCC2")
		(14 "In6.Cu" signal "L07_GND3")
		(16 "In7.Cu" signal "L08_SIG2")
		(18 "In8.Cu" signal "L09_GND4")
		(2 "B.Cu" signal "BOTTOM")
		(9 "F.Adhes" user "F.Adhesive")
		(11 "B.Adhes" user "B.Adhesive")
		(13 "F.Paste" user "Package Geometry/Pastemask Top")
		(15 "B.Paste" user "Package Geometry/Pastemask Bottom")
		(5 "F.SilkS" user "Ref Des/Silkscreen Top")
		(7 "B.SilkS" user "Ref Des/Silkscreen Bottom")
		(1 "F.Mask" user "Board Geometry/Soldermask Top")
		(3 "B.Mask" user "Board Geometry/Soldermask Bottom")
		(17 "Dwgs.User" user "User.Drawings")
		(19 "Cmts.User" user "User.Comments")
		(21 "Eco1.User" user "User.Eco1")
		(23 "Eco2.User" user "User.Eco2")
		(25 "Edge.Cuts" user "Board Geometry/Outline")
		(27 "Margin" user)
		(31 "F.CrtYd" user "Package Geometry/Place Bound Top")
		(29 "B.CrtYd" user "Package Geometry/Place Bound Bottom")
		(35 "F.Fab" user "Ref Des/Assembly Top")
		(33 "B.Fab" user "Ref Des/Assembly Bottom")
	)
	(footprint ""
		(layer "B.Cu")
		(at 111.633 -61.976 90)
		(property "Reference" "R219"
			(at 3.302 -0.03937 270)
			(unlocked yes)
			(layer "B.SilkS")
			(effects
				(font
					(size 0.7874 0.5842)
					(thickness 0.1524)
				)
				(justify mirror)
			)
		)
		(property "Value" "VAL*"
			(at -0.02032 2.13233 90)
			(unlocked yes)
			(layer "B.Fab")
			(hide yes)
			(effects
				(font
					(size 0.7874 0.5842)
					(thickness 0.1524)
				)
				(justify mirror)
			)
		)
		(property "Device Type" "RESISTOR-G155-11002-01,10KOHM,A"
			(at -0.008382 1.210564 90)
			(unlocked yes)
			(layer "B.Fab")
			(hide yes)
			(effects
				(font
					(size 0.7874 0.5842)
					(thickness 0.1524)
				)
				(justify mirror)
			)
		)
		(property "User Part Number" "PARTNUM*"
			(at -0.02032 4.024884 90)
			(unlocked yes)
			(layer "Cmts.User")
			(hide yes)
			(effects
				(font
					(size 0.7874 0.5842)
					(thickness 0.1524)
				)
				(justify mirror)
			)
		)
		(property "Tolerance" "TOL*"
			(at -0.044704 3.05435 90)
			(unlocked yes)
			(layer "Cmts.User")
			(hide yes)
			(effects
				(font
					(size 0.7874 0.5842)
					(thickness 0.1524)
				)
				(justify mirror)
			)
		)
		(duplicate_pad_numbers_are_jumpers no)
		(fp_line
			(start 1.143 -0.5588)
			(end 1.143 0.5588)
			(stroke
				(width 0.1)
				(type default)
			)
			(layer "B.SilkS")
		)
		(fp_line
			(start -1.143 -0.5588)
			(end 1.143 -0.5588)
			(stroke
				(width 0.1)
				(type default)
			)
			(layer "B.SilkS")
		)
		(fp_line
			(start 1.143 0.5588)
			(end -1.143 0.5588)
			(stroke
				(width 0.1)
				(type default)
			)
			(layer "B.SilkS")
		)
		(fp_line
			(start -1.143 0.5588)
			(end -1.143 -0.5588)
			(stroke
				(width 0.1)
				(type default)
			)
			(layer "B.SilkS")
		)
		(fp_rect
			(start -1.143 0.5588)
			(end 1.143 -0.5588)
			(stroke
				(width 0)
				(type default)
			)
			(fill no)
			(layer "B.CrtYd")
		)
		(fp_line
			(start 0.508 -0.3048)
			(end 0.508 0.3048)
			(stroke
				(width 0.1)
				(type default)
			)
			(layer "B.Fab")
		)
		(fp_line
			(start -0.508 -0.3048)
			(end 0.508 -0.3048)
			(stroke
				(width 0.1)
				(type default)
			)
			(layer "B.Fab")
		)
		(fp_line
			(start 0.508 0.3048)
			(end -0.508 0.3048)
			(stroke
				(width 0.1)
				(type default)
			)
			(layer "B.Fab")
		)
		(fp_line
			(start -0.508 0.3048)
			(end -0.508 -0.3048)
			(stroke
				(width 0.1)
				(type default)
			)
			(layer "B.Fab")
		)
		(pad "1" smd rect
			(at 0.5334 0 270)
			(size 0.7112 0.6096)
			(layers "B.Cu" "B.Mask" "B.Paste")
			(net "XP3R3V_FPGA")
		)
		(pad "2" smd rect
			(at -0.5334 0 270)
			(size 0.7112 0.6096)
			(layers "B.Cu" "B.Mask" "B.Paste")
			(net "FPGA_BRD_REV0")
		)
		(zone
			(layer "B.Cu")
			(hatch none 0.5)
			(connect_pads
				(clearance 0)
			)
			(min_thickness 0.25)
			(keepout
				(tracks allowed)
				(vias not_allowed)
				(pads allowed)
				(copperpour not_allowed)
				(footprints allowed)
			)
			(placement
				(enabled no)
				(sheetname "")
			)
			(fill
				(thermal_gap 0.5)
				(thermal_bridge_width 0.5)
				(island_removal_mode 0)
			)
			(polygon
				(pts
					(xy 111.9378 -61.8998) (xy 111.9378 -62.0522) (xy 111.3282 -62.0522) (xy 111.3282 -61.8998)
				)
			)
		)
	)
	(footprint ""
		(layer "B.Cu")
		(at 26.797 -94.234 90)
		(property "Reference" "R18"
			(at 2.54 0.34163 270)
			(unlocked yes)
			(layer "B.SilkS")
			(effects
				(font
					(size 0.7874 0.5842)
					(thickness 0.1524)
				)
				(justify mirror)
			)
		)
		(property "Value" "VAL*"
			(at -0.02032 2.13233 90)
			(unlocked yes)
			(layer "B.Fab")
			(hide yes)
			(effects
				(font
					(size 0.7874 0.5842)
					(thickness 0.1524)
				)
				(justify mirror)
			)
		)
		(property "Device Type" "RESISTOR-G155-14701-01,4.7KOHMA"
			(at -0.008382 1.210564 90)
			(unlocked yes)
			(layer "B.Fab")
			(hide yes)
			(effects
				(font
					(size 0.7874 0.5842)
					(thickness 0.1524)
				)
				(justify mirror)
			)
		)
		(property "User Part Number" "PARTNUM*"
			(at -0.02032 4.024884 90)
			(unlocked yes)
			(layer "Cmts.User")
			(hide yes)
			(effects
				(font
					(size 0.7874 0.5842)
					(thickness 0.1524)
				)
				(justify mirror)
			)
		)
		(property "Tolerance" "TOL*"
			(at -0.044704 3.05435 90)
			(unlocked yes)
			(layer "Cmts.User")
			(hide yes)
			(effects
				(font
					(size 0.7874 0.5842)
					(thickness 0.1524)
				)
				(justify mirror)
			)
		)
		(duplicate_pad_numbers_are_jumpers no)
		(fp_line
			(start 1.143 -0.5588)
			(end 1.143 0.5588)
			(stroke
				(width 0.1)
				(type default)
			)
			(layer "B.SilkS")
		)
		(fp_line
			(start -1.143 -0.5588)
			(end 1.143 -0.5588)
			(stroke
				(width 0.1)
				(type default)
			)
			(layer "B.SilkS")
		)
		(fp_line
			(start 1.143 0.5588)
			(end -1.143 0.5588)
			(stroke
				(width 0.1)
				(type default)
			)
			(layer "B.SilkS")
		)
		(fp_line
			(start -1.143 0.5588)
			(end -1.143 -0.5588)
			(stroke
				(width 0.1)
				(type default)
			)
			(layer "B.SilkS")
		)
		(fp_rect
			(start -1.143 0.5588)
			(end 1.143 -0.5588)
			(stroke
				(width 0)
				(type default)
			)
			(fill no)
			(layer "B.CrtYd")
		)
		(fp_line
			(start 0.508 -0.3048)
			(end 0.508 0.3048)
			(stroke
				(width 0.1)
				(type default)
			)
			(layer "B.Fab")
		)
		(fp_line
			(start -0.508 -0.3048)
			(end 0.508 -0.3048)
			(stroke
				(width 0.1)
				(type default)
			)
			(layer "B.Fab")
		)
		(fp_line
			(start 0.508 0.3048)
			(end -0.508 0.3048)
			(stroke
				(width 0.1)
				(type default)
			)
			(layer "B.Fab")
		)
		(fp_line
			(start -0.508 0.3048)
			(end -0.508 -0.3048)
			(stroke
				(width 0.1)
				(type default)
			)
			(layer "B.Fab")
		)
		(pad "1" smd rect
			(at 0.5334 0 270)
			(size 0.7112 0.6096)
			(layers "B.Cu" "B.Mask" "B.Paste")
			(net "XP5R0V_FT4232")
		)
		(pad "2" smd rect
			(at -0.5334 0 270)
			(size 0.7112 0.6096)
			(layers "B.Cu" "B.Mask" "B.Paste")
			(net "FT_USB_DETECT")
		)
		(zone
			(layer "B.Cu")
			(hatch none 0.5)
			(connect_pads
				(clearance 0)
			)
			(min_thickness 0.25)
			(keepout
				(tracks allowed)
				(vias not_allowed)
				(pads allowed)
				(copperpour not_allowed)
				(footprints allowed)
			)
			(placement
				(enabled no)
				(sheetname "")
			)
			(fill
				(thermal_gap 0.5)
				(thermal_bridge_width 0.5)
				(island_removal_mode 0)
			)
			(polygon
				(pts
					(xy 27.1018 -94.1578) (xy 27.1018 -94.3102) (xy 26.4922 -94.3102) (xy 26.4922 -94.1578)
				)
			)
		)
	)
)
